G04 ================== begin FILE IDENTIFICATION RECORD ==================*
G04 Layout Name:  12523-1.brd*
G04 Film Name:    L2GND*
G04 File Format:  Gerber RS274X*
G04 File Origin:  Cadence Allegro 16.2-s031*
G04 Origin Date:  Fri Oct 19 14:59:13 2012*
G04 *
G04 Layer:  VIA CLASS/L2GND*
G04 Layer:  PIN/L2GND*
G04 Layer:  ETCH/L2GND*
G04 Layer:  DRAWING FORMAT/LAYER_PCB_STORY*
G04 Layer:  DRAWING FORMAT/LAYER_L2GND*
G04 *
G04 Offset:    (0.00 0.00)*
G04 Mirror:    No*
G04 Mode:      Negative*
G04 Rotation:  0*
G04 FullContactRelief:  No*
G04 UndefLineWidth:     6.00*
G04 ================== end FILE IDENTIFICATION RECORD ====================*
%FSLAX35Y35*MOIN*%
%IR0*IPPOS*OFA0.00000B0.00000*MIA0B0*SFA1.00000B1.00000*%
%AMMACRO17*
4,1,14,.0267,.01255,
.028474,.007723,
.029382,.002661,
.029398,-.002481,
.02852,-.007549,
.026776,-.012386,
.0267,-.01255,
.03042,-.01628,
.032785,-.01075,
.034154,-.004894,
.034484,.001111,
.033768,.007082,
.032025,.012838,
.03042,.01628,
.0267,.01255,
90.*
4,1,14,.01255,-.0267,
.007723,-.028474,
.002661,-.029382,
-.002481,-.029398,
-.007549,-.02852,
-.012386,-.026776,
-.01255,-.0267,
-.01628,-.03042,
-.01075,-.032785,
-.004894,-.034154,
.001111,-.034484,
.007082,-.033768,
.012838,-.032025,
.01628,-.03042,
.01255,-.0267,
90.*
4,1,14,-.0267,-.01255,
-.028474,-.007723,
-.029382,-.002661,
-.029398,.002481,
-.02852,.007549,
-.026776,.012386,
-.0267,.01255,
-.03042,.01628,
-.032785,.01075,
-.034154,.004894,
-.034484,-.001111,
-.033768,-.007082,
-.032025,-.012838,
-.03042,-.01628,
-.0267,-.01255,
90.*
4,1,14,-.01255,.0267,
-.007723,.028474,
-.002661,.029382,
.002481,.029398,
.007549,.02852,
.012386,.026776,
.01255,.0267,
.01628,.03042,
.01075,.032785,
.004894,.034154,
-.001111,.034484,
-.007082,.033768,
-.012838,.032025,
-.01628,.03042,
-.01255,.0267,
90.*
%
%ADD17MACRO17*%
%AMMACRO16*
4,1,16,.07909,.0508,
.08671,.036294,
.091695,.020686,
.093894,.004449,
.09324,-.011923,
.089753,-.027933,
.083539,-.043094,
.07909,-.0508,
.0827,-.05442,
.090894,-.039233,
.096325,-.022853,
.09883,-.005779,
.098332,.01147,
.094847,.028371,
.088479,.04441,
.0827,.05442,
.07909,.0508,
0.0*
4,1,16,.0508,-.07909,
.036294,-.08671,
.020686,-.091695,
.004449,-.093894,
-.011923,-.09324,
-.027933,-.089753,
-.043094,-.083539,
-.0508,-.07909,
-.05442,-.0827,
-.039233,-.090894,
-.022853,-.096325,
-.005779,-.09883,
.01147,-.098332,
.028371,-.094847,
.04441,-.088479,
.05442,-.0827,
.0508,-.07909,
0.0*
4,1,16,-.07909,-.0508,
-.08671,-.036294,
-.091695,-.020686,
-.093894,-.004449,
-.09324,.011923,
-.089753,.027933,
-.083539,.043094,
-.07909,.0508,
-.0827,.05442,
-.090894,.039233,
-.096325,.022853,
-.09883,.005779,
-.098332,-.01147,
-.094847,-.028371,
-.088479,-.04441,
-.0827,-.05442,
-.07909,-.0508,
0.0*
4,1,16,-.0508,.07909,
-.036294,.08671,
-.020686,.091695,
-.004449,.093894,
.011923,.09324,
.027933,.089753,
.043094,.083539,
.0508,.07909,
.05442,.0827,
.039233,.090894,
.022853,.096325,
.005779,.09883,
-.01147,.098332,
-.028371,.094847,
-.04441,.088479,
-.05442,.0827,
-.0508,.07909,
0.0*
%
%ADD16MACRO16*%
%ADD19C,.062*%
%ADD13C,.036*%
%ADD20C,.065*%
%ADD18C,.069*%
%AMMACRO15*
4,1,15,.00398,.00044,
.003999,.000208,
.004004,-.000025,
.003996,-.000258,
.00398,-.00044,
.00483,-.00129,
.004897,-.001007,
.004947,-.000721,
.004981,-.000432,
.004997,-.000141,
.004997,.000149,
.00498,.00044,
.004946,.000729,
.004895,.001015,
.00483,.00129,
.00398,.00044,
90.*
4,1,15,.00044,-.00398,
.000208,-.003999,
-.000025,-.004004,
-.000258,-.003996,
-.00044,-.00398,
-.00129,-.00483,
-.001007,-.004897,
-.000721,-.004947,
-.000432,-.004981,
-.000141,-.004997,
.000149,-.004997,
.00044,-.00498,
.000729,-.004946,
.001015,-.004895,
.00129,-.00483,
.00044,-.00398,
90.*
4,1,15,-.00398,-.00044,
-.003999,-.000208,
-.004004,.000025,
-.003996,.000258,
-.00398,.00044,
-.00483,.00129,
-.004897,.001007,
-.004947,.000721,
-.004981,.000432,
-.004997,.000141,
-.004997,-.000149,
-.00498,-.00044,
-.004946,-.000729,
-.004895,-.001015,
-.00483,-.00129,
-.00398,-.00044,
90.*
4,1,15,-.00044,.00398,
-.000208,.003999,
.000025,.004004,
.000258,.003996,
.00044,.00398,
.00129,.00483,
.001007,.004897,
.000721,.004947,
.000432,.004981,
.000141,.004997,
-.000149,.004997,
-.00044,.00498,
-.000729,.004946,
-.001015,.004895,
-.00129,.00483,
-.00044,.00398,
90.*
%
%ADD15MACRO15*%
%AMMACRO14*
4,1,15,.00398,.00044,
.003999,.000208,
.004004,-.000025,
.003996,-.000258,
.00398,-.00044,
.00483,-.00129,
.004897,-.001007,
.004947,-.000721,
.004981,-.000432,
.004997,-.000141,
.004997,.000149,
.00498,.00044,
.004946,.000729,
.004895,.001015,
.00483,.00129,
.00398,.00044,
0.0*
4,1,15,.00044,-.00398,
.000208,-.003999,
-.000025,-.004004,
-.000258,-.003996,
-.00044,-.00398,
-.00129,-.00483,
-.001007,-.004897,
-.000721,-.004947,
-.000432,-.004981,
-.000141,-.004997,
.000149,-.004997,
.00044,-.00498,
.000729,-.004946,
.001015,-.004895,
.00129,-.00483,
.00044,-.00398,
0.0*
4,1,15,-.00398,-.00044,
-.003999,-.000208,
-.004004,.000025,
-.003996,.000258,
-.00398,.00044,
-.00483,.00129,
-.004897,.001007,
-.004947,.000721,
-.004981,.000432,
-.004997,.000141,
-.004997,-.000149,
-.00498,-.00044,
-.004946,-.000729,
-.004895,-.001015,
-.00483,-.00129,
-.00398,-.00044,
0.0*
4,1,15,-.00044,.00398,
-.000208,.003999,
.000025,.004004,
.000258,.003996,
.00044,.00398,
.00129,.00483,
.001007,.004897,
.000721,.004947,
.000432,.004981,
.000141,.004997,
-.000149,.004997,
-.00044,.00498,
-.000729,.004946,
-.001015,.004895,
-.00129,.00483,
-.00044,.00398,
0.0*
%
%ADD14MACRO14*%
%ADD10C,.114*%
%ADD21C,.186*%
%AMMACRO12*
4,1,15,.00398,.00044,
.003999,.000208,
.004004,-.000025,
.003996,-.000258,
.00398,-.00044,
.00483,-.00129,
.004897,-.001007,
.004947,-.000721,
.004981,-.000432,
.004997,-.000141,
.004997,.000149,
.00498,.00044,
.004946,.000729,
.004895,.001015,
.00483,.00129,
.00398,.00044,
180.*
4,1,15,.00044,-.00398,
.000208,-.003999,
-.000025,-.004004,
-.000258,-.003996,
-.00044,-.00398,
-.00129,-.00483,
-.001007,-.004897,
-.000721,-.004947,
-.000432,-.004981,
-.000141,-.004997,
.000149,-.004997,
.00044,-.00498,
.000729,-.004946,
.001015,-.004895,
.00129,-.00483,
.00044,-.00398,
180.*
4,1,15,-.00398,-.00044,
-.003999,-.000208,
-.004004,.000025,
-.003996,.000258,
-.00398,.00044,
-.00483,.00129,
-.004897,.001007,
-.004947,.000721,
-.004981,.000432,
-.004997,.000141,
-.004997,-.000149,
-.00498,-.00044,
-.004946,-.000729,
-.004895,-.001015,
-.00483,-.00129,
-.00398,-.00044,
180.*
4,1,15,-.00044,.00398,
-.000208,.003999,
.000025,.004004,
.000258,.003996,
.00044,.00398,
.00129,.00483,
.001007,.004897,
.000721,.004947,
.000432,.004981,
.000141,.004997,
-.000149,.004997,
-.00044,.00498,
-.000729,.004946,
-.001015,.004895,
-.00129,.00483,
-.00044,.00398,
180.*
%
%ADD12MACRO12*%
%AMMACRO11*
4,1,16,.07256,.04427,
.079145,.030998,
.083325,.016783,
.084974,.002059,
.08404,-.012728,
.080553,-.027128,
.074619,-.040704,
.07256,-.04427,
.07619,-.04791,
.083352,-.033952,
.087981,-.018962,
.089937,-.003396,
.089161,.012273,
.085675,.027569,
.079586,.042027,
.07619,.04791,
.07256,.04427,
0.0*
4,1,16,.04427,-.07256,
.030998,-.079145,
.016783,-.083325,
.002059,-.084974,
-.012728,-.08404,
-.027128,-.080553,
-.040704,-.074619,
-.04427,-.07256,
-.04791,-.07619,
-.033952,-.083352,
-.018962,-.087981,
-.003396,-.089937,
.012273,-.089161,
.027569,-.085675,
.042027,-.079586,
.04791,-.07619,
.04427,-.07256,
0.0*
4,1,16,-.07256,-.04427,
-.079145,-.030998,
-.083325,-.016783,
-.084974,-.002059,
-.08404,.012728,
-.080553,.027128,
-.074619,.040704,
-.07256,.04427,
-.07619,.04791,
-.083352,.033952,
-.087981,.018962,
-.089937,.003396,
-.089161,-.012273,
-.085675,-.027569,
-.079586,-.042027,
-.07619,-.04791,
-.07256,-.04427,
0.0*
4,1,16,-.04427,.07256,
-.030998,.079145,
-.016783,.083325,
-.002059,.084974,
.012728,.08404,
.027128,.080553,
.040704,.074619,
.04427,.07256,
.04791,.07619,
.033952,.083352,
.018962,.087981,
.003396,.089937,
-.012273,.089161,
-.027569,.085675,
-.042027,.079586,
-.04791,.07619,
-.04427,.07256,
0.0*
%
%ADD11MACRO11*%
%ADD22C,.02*%
%ADD23C,.006*%
%ADD25C,.05806*%
%ADD24C,.18206*%
G75*
%LPD*%
G75*
G36*
G01X-49307Y-6000D02*
X646394D01*
Y478441D01*
X-49307D01*
Y-6000D01*
G37*
%LPC*%
G75*
G36*
G01X637390Y388524D02*
G02X636975Y387748I-933J0D01*
G01X627907Y381704D01*
G02X627390Y381547I-518J776D01*
G01X545906D01*
G03X538965Y374606I0J-6941D01*
G01Y357677D01*
G03X545906Y350736I6941J0D01*
G01X627391D01*
G02X627908Y350580I0J-933D01*
G01X636975Y344536D01*
G02X637390Y343759I-518J-776D01*
G01X637371Y320909D01*
G02X636457Y319787I-914J-189D01*
G01X624646D01*
G03X617705Y312846I0J-6941D01*
G01Y135972D01*
G03X624646Y129031I6941J0D01*
G01X636457D01*
G02X637390Y128098I0J-933D01*
G01Y3937D01*
G02X636457Y3004I-933J0D01*
G01X3937D01*
G02X3004Y3937I0J933D01*
G01Y79500D01*
X38086D01*
X55086Y62500D01*
X56000D01*
X547854Y62440D01*
X591000Y105586D01*
Y142086D01*
X609500Y160586D01*
Y195414D01*
X605914Y199000D01*
X566086D01*
X554586Y187500D01*
X417914D01*
X410914Y194440D01*
X-33307D01*
Y289043D01*
X-1378D01*
G03Y297807I0J4382D01*
G01X-33307D01*
Y362941D01*
X-3937D01*
G03X3004Y369882I0J6941D01*
G01Y468504D01*
G02X3937Y469437I933J0D01*
G01X636457D01*
G02X637390Y468504I0J-933D01*
G01Y388524D01*
G37*
G36*
G01X-33307Y113910D02*
Y192500D01*
X410086D01*
X417086Y185500D01*
X555414D01*
X566914Y197000D01*
X605086D01*
X607500Y194586D01*
Y161414D01*
X589000Y142914D01*
Y106414D01*
X547026Y64440D01*
X56000Y64500D01*
X55914D01*
X38914Y81500D01*
X3004D01*
Y106969D01*
G03X-3937Y113910I-6941J0D01*
G01X-33307D01*
G37*
%LPD*%
G75*
G36*
G01X25118Y219438D02*
X21181D01*
G02X14242Y226378I1J6940D01*
G01Y246063D01*
G02X21181Y253002I6939J0D01*
G01X25118D01*
G02X32058Y246063I1J-6939D01*
G01Y226378D01*
G02X25118Y219438I-6940J0D01*
G37*
G54D25*
X599055Y90551D03*
Y59055D03*
G54D24*
X600709Y311909D03*
Y136909D03*
G54D17*
X570709Y161889D03*
X580709D03*
X570709Y191889D03*
X580709D03*
X570709Y181889D03*
X580709D03*
X570709Y171889D03*
X580709D03*
X570709Y276929D03*
X580709D03*
X570709Y266929D03*
X580709D03*
X570709Y256929D03*
X580709D03*
X570709Y286929D03*
X580709D03*
X590709Y161889D03*
X600709D03*
Y214409D03*
X590709Y204409D03*
Y191889D03*
X600709D03*
X590709Y181889D03*
X600709D03*
X590709Y171889D03*
X600709D03*
X590709Y244409D03*
Y276929D03*
X600709D03*
X590709Y266929D03*
X600709D03*
X590709Y256929D03*
X600709D03*
Y234409D03*
X590709Y224409D03*
Y286929D03*
X600709D03*
G54D16*
X498661Y23622D03*
X589212Y448818D03*
G54D19*
X599055Y59055D03*
Y90551D03*
G54D13*
X3398Y326936D03*
X2334Y318654D03*
X1494Y343705D03*
X5694D03*
X10000Y332000D03*
X30923Y335665D03*
X26723D03*
X57398Y348682D03*
X52705Y348626D03*
X48325Y348514D03*
X37500Y386500D03*
X60052Y394674D03*
X55352D03*
X51094Y394478D03*
X520500Y331000D03*
X561500Y232000D03*
X557000Y231500D03*
X543900Y314000D03*
X600000Y337500D03*
Y342000D03*
X595500D03*
Y337500D03*
X612798Y413000D03*
X617798D03*
G54D20*
X596102Y66929D03*
X602008Y74803D03*
X596102Y82677D03*
G54D18*
X570709Y214409D03*
X580709D03*
X570709Y204409D03*
X580709D03*
X570709Y244409D03*
X580709D03*
X570709Y234409D03*
X580709D03*
X570709Y224409D03*
X580709D03*
X590709Y214409D03*
X600709Y204409D03*
Y244409D03*
X590709Y234409D03*
X600709Y224409D03*
G54D15*
X22000Y387500D03*
X55500Y417000D03*
X512500Y323000D03*
X492000Y321000D03*
X506500Y305500D03*
X520381Y300757D03*
X537136Y326402D03*
X525161Y311000D03*
G54D14*
X25500Y353000D03*
X25000Y343000D03*
X33986Y362933D03*
X22000Y374500D03*
X61898Y358936D03*
X546600Y257971D03*
G54D10*
X-23621Y15748D03*
Y937008D03*
X1312285Y15747D03*
G54D21*
X600709Y136909D03*
Y311909D03*
G54D12*
X6419Y116482D03*
X-3350Y117504D03*
X6419Y126482D03*
X-3581D03*
X6419Y136482D03*
X-3581D03*
X6419Y146482D03*
X-3581D03*
X6419Y156482D03*
X-3581D03*
X-2602Y206936D03*
X7398D03*
X-2602Y216936D03*
X7398D03*
X6419Y166482D03*
X-3581D03*
Y176482D03*
X6419D03*
X-2602Y226936D03*
X7398D03*
X-2602Y246936D03*
X7398D03*
X-2602Y236936D03*
X7398D03*
Y256936D03*
X-2602D03*
Y266936D03*
X7398D03*
Y276936D03*
X-2602D03*
X7398Y286936D03*
X-2948Y302202D03*
X-2602Y316436D03*
X-7102Y327202D03*
X-6940Y316247D03*
X-6602Y347202D03*
X-7102Y337202D03*
X-6602Y357202D03*
X6898Y387436D03*
X6398Y369936D03*
X6898Y445436D03*
Y465436D03*
X16419Y6482D03*
Y26482D03*
X36419Y6482D03*
Y26482D03*
X56419Y46482D03*
X16419Y86482D03*
X36419D03*
X56419Y66482D03*
Y86482D03*
X26419Y116482D03*
X16419D03*
X26419Y126482D03*
X16419D03*
X26419Y136482D03*
X16419D03*
X26419Y146482D03*
X16419D03*
X26419Y156482D03*
X16419D03*
X36419Y126482D03*
X16419Y106482D03*
X36419D03*
Y146482D03*
X56419Y126482D03*
Y106482D03*
Y146482D03*
X27398Y206936D03*
X17398D03*
X27398Y216936D03*
X17398D03*
X26419Y186482D03*
X16419D03*
X26419Y166482D03*
X16419D03*
Y176482D03*
X26419D03*
X36419Y186482D03*
Y166482D03*
X56419Y186482D03*
Y166482D03*
X57398Y206936D03*
X37398D03*
X17398Y256936D03*
X27398D03*
Y266936D03*
X17398D03*
X57398Y226936D03*
X36769D03*
X57398Y246936D03*
Y266936D03*
X36769Y246936D03*
X37398Y266936D03*
X17398Y276936D03*
X27398Y286936D03*
X17398D03*
X27398Y276936D03*
X57398Y286936D03*
X37398D03*
X64398Y304436D03*
X34898Y344936D03*
X62398Y338436D03*
X62000Y442500D03*
X35830Y442464D03*
X19898Y465436D03*
X39898D03*
X76419Y46482D03*
X116419D03*
X96419D03*
X76419Y66482D03*
Y86482D03*
X116419Y66482D03*
X96419D03*
X116419Y86482D03*
X96419D03*
X76419Y126482D03*
Y106482D03*
Y146482D03*
X116419Y126482D03*
Y106482D03*
X96419Y126482D03*
Y106482D03*
X116419Y146482D03*
X96419D03*
X76419Y186482D03*
Y166482D03*
X77398Y206936D03*
X116419Y186482D03*
Y166482D03*
X96419Y186482D03*
Y166482D03*
X117398Y206936D03*
X97398D03*
X77398Y226936D03*
Y246936D03*
Y266936D03*
X117398Y226936D03*
X97398D03*
X117398Y246936D03*
X97398D03*
Y266936D03*
X116398D03*
X77398Y286936D03*
X86398Y303936D03*
X97398Y286936D03*
X116398D03*
X77898Y338436D03*
X78398Y358436D03*
X115330Y337964D03*
X96398Y337936D03*
X115330Y377964D03*
Y357964D03*
X95330Y377964D03*
Y357964D03*
X105330Y442964D03*
X85330D03*
X75500Y417500D03*
X115330Y417964D03*
X95330D03*
X91500Y465500D03*
X117500D03*
X67830Y465464D03*
X136419Y6482D03*
Y46482D03*
X176419Y6482D03*
Y26482D03*
X156419Y6482D03*
Y26482D03*
X176419Y46482D03*
X156419D03*
X136419Y66482D03*
Y86482D03*
X176419Y66482D03*
X156419D03*
X176419Y86482D03*
X156419D03*
X136419Y126482D03*
Y106482D03*
Y146482D03*
X176419Y126482D03*
Y106482D03*
X156419Y126482D03*
Y106482D03*
X176419Y146482D03*
X156419D03*
X136419Y186482D03*
Y166482D03*
X137398Y206936D03*
X176419Y186482D03*
Y166482D03*
X156419Y186482D03*
Y166482D03*
X177398Y206436D03*
X157398Y206936D03*
X137398Y226936D03*
Y246936D03*
Y266936D03*
X177398Y226936D03*
X157398D03*
X177398Y246936D03*
Y266936D03*
X157398Y246936D03*
Y266936D03*
X137398Y286936D03*
X177398D03*
X157398D03*
X135330Y337964D03*
Y377964D03*
Y357964D03*
X175330Y337964D03*
X155330D03*
X175330Y377964D03*
Y357964D03*
X155330Y377964D03*
Y357964D03*
X132000Y442500D03*
X135330Y417964D03*
X175500Y442000D03*
X175330Y417964D03*
X155000Y442000D03*
X155330Y417964D03*
X139898Y465436D03*
X159898D03*
X196419Y6482D03*
Y26482D03*
Y46482D03*
X236419Y6482D03*
Y26482D03*
X216419Y6482D03*
Y26482D03*
X236419Y46482D03*
X216419D03*
X196419Y66482D03*
Y86482D03*
X236419Y66482D03*
X216419D03*
X236419Y86482D03*
X216419D03*
X196419Y126482D03*
Y106482D03*
Y146482D03*
X236419Y126482D03*
Y106482D03*
X216419Y126482D03*
Y106482D03*
X236419Y146482D03*
X216419D03*
X196419Y186482D03*
Y166482D03*
X197398Y206436D03*
X236419Y186482D03*
Y166482D03*
X216419Y186482D03*
Y166482D03*
X217398Y206436D03*
X197398Y226936D03*
Y246936D03*
Y266936D03*
X217398Y226936D03*
Y246936D03*
Y266936D03*
X197398Y286936D03*
X217398D03*
X195330Y337964D03*
Y377964D03*
Y357964D03*
X235330Y337964D03*
X215330D03*
X235330Y377964D03*
Y357964D03*
X215330Y377964D03*
Y357964D03*
X196000Y442500D03*
X195330Y417964D03*
X235830Y442464D03*
X235330Y417964D03*
X215830Y442464D03*
X215330Y417964D03*
X179898Y465436D03*
X219898D03*
X199898D03*
X256419Y6482D03*
Y26482D03*
X276419Y6482D03*
Y26482D03*
X256419Y46482D03*
X276419D03*
X256419Y66482D03*
X273500Y66500D03*
X256419Y86482D03*
X274500Y86500D03*
X256419Y126482D03*
X276419D03*
X256419Y106482D03*
X274500Y106500D03*
X256419Y146482D03*
X276419D03*
X237398Y206436D03*
X256419Y186482D03*
X275500Y186500D03*
X251500Y166500D03*
X276419Y166482D03*
X257398Y206436D03*
X277398D03*
X237398Y226936D03*
Y246936D03*
Y266936D03*
X257398Y226936D03*
X277398D03*
X257398Y246936D03*
X277398D03*
X257398Y266936D03*
X277398D03*
X237398Y286936D03*
X257398D03*
X279398D03*
X255330Y337964D03*
X275330D03*
X255330Y377964D03*
X275330D03*
X255330Y357964D03*
X275330D03*
X255830Y442464D03*
X275830D03*
X255330Y417964D03*
X275330D03*
X239898Y465436D03*
X279898D03*
X259898D03*
X296419Y6482D03*
Y26482D03*
Y46482D03*
X316419Y6482D03*
Y26482D03*
X336419Y6482D03*
Y26482D03*
X316419Y46482D03*
X336419D03*
X302000Y67000D03*
X301000Y86500D03*
X316419Y66482D03*
X336419D03*
X316419Y86482D03*
X336419D03*
X296419Y126482D03*
X300000Y106500D03*
X296419Y146482D03*
X316419Y126482D03*
X336419D03*
X316419Y106482D03*
X336419D03*
X316419Y146482D03*
X336419D03*
X296419Y186482D03*
X295500Y169000D03*
X297398Y206436D03*
X317500Y186500D03*
X336419Y186482D03*
X317000Y166500D03*
X338500Y166000D03*
X317398Y206436D03*
X337398D03*
X297398Y226936D03*
Y246936D03*
Y266936D03*
X317398Y226936D03*
X337398D03*
X317398Y246936D03*
X337398D03*
X317398Y266936D03*
X337398D03*
X300398Y286936D03*
X317398D03*
X337398D03*
X295330Y337964D03*
Y377964D03*
Y357964D03*
X315330Y337964D03*
X335330D03*
X315330Y377964D03*
X335330D03*
X315330Y357964D03*
X335330D03*
X295830Y442464D03*
X295330Y417964D03*
X315830Y442464D03*
X335830D03*
X315330Y417964D03*
X335330D03*
X299898Y465436D03*
X339898D03*
X319898D03*
X356419Y6482D03*
Y26482D03*
Y46482D03*
X376419Y6482D03*
Y26482D03*
X396419Y6482D03*
Y26482D03*
X376419Y46482D03*
X396419D03*
X356419Y66482D03*
Y86482D03*
X376419Y66482D03*
X396419D03*
X376419Y86482D03*
X396419D03*
X356419Y126482D03*
Y106482D03*
Y146482D03*
X376419Y126482D03*
X396419D03*
X376419Y106482D03*
X396419D03*
X376419Y146482D03*
X396419D03*
X357500Y186500D03*
X354500Y166500D03*
X357398Y206436D03*
X376419Y186482D03*
X396419D03*
X380000Y166500D03*
X396419Y166482D03*
X377398Y206436D03*
X397398D03*
X357398Y226936D03*
Y246936D03*
Y266936D03*
X377398Y226936D03*
X397398D03*
X377398Y246936D03*
X397398D03*
X377398Y266936D03*
X397398D03*
X357398Y286936D03*
X377398D03*
X397398D03*
X355330Y337964D03*
Y377964D03*
Y357964D03*
X375330Y337964D03*
X395330D03*
X375330Y377964D03*
X395330D03*
X375330Y357964D03*
X395330D03*
X355830Y442464D03*
X355330Y417964D03*
X375830Y442464D03*
X395830D03*
X375330Y417964D03*
X395330D03*
X399898Y465436D03*
X379898D03*
X359898D03*
X416419Y6482D03*
Y26482D03*
X436419Y6482D03*
X416419Y46482D03*
X436419D03*
X456419D03*
X416419Y66482D03*
X436419D03*
X456419D03*
X416419Y86482D03*
X436419D03*
X456419D03*
X416419Y126482D03*
X436419D03*
X456419D03*
X416419Y106482D03*
X436419D03*
X456419D03*
X416419Y146482D03*
X436419D03*
X456419D03*
X416500Y166000D03*
X417519Y174482D03*
Y170282D03*
X425919D03*
X421719D03*
Y174482D03*
X431100Y174500D03*
Y170300D03*
X439500D03*
Y174500D03*
X435300Y170300D03*
Y174500D03*
X444100D03*
Y170300D03*
X452500D03*
Y174500D03*
X448300Y170300D03*
Y174500D03*
X457100Y175000D03*
Y170800D03*
X461300D03*
Y175000D03*
X418300Y197500D03*
Y201700D03*
X422500D03*
X426700D03*
X422500Y197500D03*
X426700D03*
X431300D03*
Y201700D03*
X435500D03*
X439700D03*
X435500Y197500D03*
X439700D03*
X444800D03*
Y201700D03*
X449000D03*
X453200D03*
X449000Y197500D03*
X453200D03*
X457800D03*
Y201700D03*
X462000D03*
Y197500D03*
X425919Y174482D03*
X436500Y166000D03*
X456500Y166500D03*
X417398Y206436D03*
X437398D03*
X457398D03*
X417398Y226936D03*
X437398D03*
X457398D03*
X417398Y246936D03*
X437398D03*
X457398D03*
X437398Y266936D03*
X457398D03*
X418398D03*
X437398Y286936D03*
X457398D03*
X418398D03*
X415330Y337964D03*
X435398Y338436D03*
X455398D03*
X415330Y377964D03*
Y357964D03*
X435398Y358436D03*
Y378436D03*
X455398Y358436D03*
Y378436D03*
X435830Y442464D03*
X455830D03*
X435330Y417964D03*
X455330D03*
X415830Y442464D03*
X415330Y417964D03*
X459898Y465436D03*
X439898D03*
X419898D03*
X516419Y6482D03*
X476419Y46482D03*
X496419D03*
X516419D03*
Y66482D03*
X476419D03*
X496419D03*
X516419Y86482D03*
X496419D03*
X476419D03*
Y126482D03*
X516419D03*
X496419D03*
X516419Y106482D03*
X496419D03*
X476419D03*
X485443Y160670D03*
X481243D03*
X493843D03*
X489643D03*
X476419Y146482D03*
X516419D03*
X496419D03*
X519221Y160912D03*
X510821D03*
X506621D03*
X515021D03*
X465500Y170800D03*
Y175000D03*
X466200Y201700D03*
Y197500D03*
X485443Y164870D03*
X481243D03*
X493843D03*
X489643D03*
X477284Y174586D03*
X473084D03*
Y170386D03*
X477284D03*
X498395Y174685D03*
Y170485D03*
X492911Y206602D03*
X488711D03*
X492911Y210802D03*
X488711D03*
X484511D03*
Y206602D03*
X480311Y210802D03*
Y206602D03*
X498052Y200389D03*
Y196189D03*
X477087Y201172D03*
X472887D03*
X477087Y196972D03*
X472887D03*
X519221Y165112D03*
X510821D03*
X506621D03*
X515021D03*
X502595Y174685D03*
Y170485D03*
X506135Y210557D03*
X510335D03*
X514535D03*
X518735D03*
X506135Y206357D03*
X510335D03*
X514535D03*
X518735D03*
X502252Y200389D03*
Y196189D03*
X497398Y226936D03*
X477398D03*
X520898Y228436D03*
X497398Y246936D03*
X477398D03*
Y266936D03*
X495398Y338436D03*
X475398D03*
X495398Y358436D03*
Y378436D03*
X475398Y358436D03*
Y378436D03*
X477000Y418000D03*
X499000Y418500D03*
X485510Y442620D03*
X505510D03*
X519898Y465436D03*
X499898D03*
X479898D03*
X533619Y6482D03*
Y26482D03*
Y46482D03*
X550819Y6482D03*
Y26482D03*
Y46482D03*
X568019Y6482D03*
Y26482D03*
Y46482D03*
X573623Y66967D03*
X536419Y66482D03*
X556419D03*
X536419Y86482D03*
X556419D03*
X576419Y106482D03*
Y126482D03*
X536419D03*
X556419D03*
X536419Y106482D03*
X556419D03*
X544476Y161322D03*
X531876D03*
X536076D03*
X540276D03*
X536419Y146482D03*
X556419D03*
X544477Y210389D03*
X544476Y165522D03*
X536076D03*
X531876D03*
X540276D03*
X552924Y175124D03*
X548724D03*
Y170924D03*
X552924D03*
X527711Y175174D03*
X523511D03*
Y170974D03*
X527711D03*
X531877Y210389D03*
X536077D03*
X540277D03*
X531877Y206189D03*
X536077D03*
X540277D03*
X544477D03*
X527761Y200632D03*
X523561D03*
X527761Y196432D03*
X523561D03*
X553171Y200877D03*
X548971D03*
X553171Y196677D03*
X548971D03*
X540898Y228436D03*
X560500Y268000D03*
X549500Y305500D03*
X559996Y282972D03*
X561500Y298000D03*
X534000Y282000D03*
X577500Y305000D03*
X634119Y26482D03*
X585219Y46482D03*
Y26482D03*
Y6482D03*
X602419Y26482D03*
Y6482D03*
X619619D03*
Y26482D03*
Y46482D03*
X634119D03*
Y6482D03*
X602419Y46482D03*
X628500Y104000D03*
X626500Y78500D03*
X611253Y65701D03*
X584543Y86671D03*
X611398Y86936D03*
X633753Y65701D03*
X633898Y86936D03*
X634000Y123500D03*
X607000D03*
X616000Y138000D03*
Y115500D03*
X594500Y117000D03*
X616000Y173500D03*
X615500Y199000D03*
X615898Y244436D03*
Y224436D03*
X615398Y266436D03*
X587500Y318500D03*
X600000Y298500D03*
X616498Y316236D03*
X615398Y284436D03*
X633398Y325436D03*
X630000Y345500D03*
Y387500D03*
X610898Y425436D03*
Y445436D03*
X632898Y404936D03*
Y444936D03*
Y424936D03*
X610898Y465436D03*
X632898Y464936D03*
G54D11*
X30157Y61023D03*
Y415354D03*
%LPC*%
G75*
G54D22*
G01X-4246Y-109426D02*
Y-189426D01*
G01D02*
X1290354D01*
G01X-4246Y-144926D02*
X1290354D01*
G01X-8246Y-93426D02*
G02I-12000J0D01*
G01X-13396D02*
G02I-6850J0D01*
G01X-20246Y-109426D02*
Y-77426D01*
G01X-4246Y-93426D02*
X-36246D01*
G01X-4246Y-109426D02*
X1290354D01*
G01X502854D02*
Y-189426D01*
G01X640354Y-109426D02*
Y-189426D01*
G01X755354Y-109426D02*
Y-189426D01*
G01X922854Y-109426D02*
Y-189426D01*
G01X1092854Y-109426D02*
Y-189426D01*
G01X1290354Y-109426D02*
Y-189426D01*
G01X1318354Y-93426D02*
G02I-12000J0D01*
G01X1313204D02*
G02I-6850J0D01*
G01X1306354Y-109426D02*
Y-77426D01*
G01X1322354Y-93426D02*
X1290354D01*
G54D23*
G01X16751Y-179426D02*
Y-161926D01*
G01X25047D02*
X16751Y-172718D01*
G01X26357Y-179426D02*
X20462Y-167760D01*
G01X34032Y-179426D02*
Y-161926D01*
X44076Y-179426D01*
Y-161926D01*
G01X56554Y-179426D02*
X54807Y-179134D01*
X53279Y-177968D01*
X51969Y-176218D01*
X51095Y-174176D01*
X50659Y-171843D01*
Y-169509D01*
X51095Y-167176D01*
X51969Y-165134D01*
X53279Y-163385D01*
X54807Y-162218D01*
X56554Y-161926D01*
X58300Y-162218D01*
X59829Y-163385D01*
X61139Y-165134D01*
X62013Y-167176D01*
X62449Y-169509D01*
Y-171843D01*
X62013Y-174176D01*
X61139Y-176218D01*
X59829Y-177968D01*
X58300Y-179134D01*
X56554Y-179426D01*
G01X69469D02*
X78639Y-161926D01*
G01X69469D02*
X78639Y-179426D01*
G01X104687D02*
Y-161926D01*
X109927D01*
X111674Y-162801D01*
X112984Y-164843D01*
X113421Y-167176D01*
X112984Y-169509D01*
X111892Y-171259D01*
X109927Y-172135D01*
X104687D01*
G01X126554Y-179426D02*
X124807Y-179134D01*
X123279Y-177968D01*
X121969Y-176218D01*
X121095Y-174176D01*
X120659Y-171843D01*
Y-169509D01*
X121095Y-167176D01*
X121969Y-165134D01*
X123279Y-163385D01*
X124807Y-162218D01*
X126554Y-161926D01*
X128300Y-162218D01*
X129829Y-163385D01*
X131139Y-165134D01*
X132013Y-167176D01*
X132449Y-169509D01*
Y-171843D01*
X132013Y-174176D01*
X131139Y-176218D01*
X129829Y-177968D01*
X128300Y-179134D01*
X126554Y-179426D01*
G01X137504Y-161926D02*
X140560Y-179426D01*
X144054Y-161926D01*
X147547Y-179426D01*
X150604Y-161926D01*
G01X165921Y-179426D02*
X157187D01*
Y-161926D01*
X165921D01*
G01X162427Y-170384D02*
X157187D01*
G01X174687Y-179426D02*
Y-161926D01*
X180146D01*
X181892Y-162801D01*
X182984Y-163968D01*
X183421Y-166301D01*
X182984Y-168635D01*
X181674Y-170093D01*
X180146Y-170968D01*
X174687D01*
G01X180146D02*
X183421Y-179426D01*
G01X214054Y-161926D02*
Y-179426D01*
G01X209032Y-161926D02*
X219076D01*
G01X227187Y-179426D02*
Y-161926D01*
X232646D01*
X234392Y-162801D01*
X235484Y-163968D01*
X235921Y-166301D01*
X235484Y-168635D01*
X234174Y-170093D01*
X232646Y-170968D01*
X227187D01*
G01X232646D02*
X235921Y-179426D01*
G01X243595D02*
X249054Y-161926D01*
X254513Y-179426D01*
G01X252547Y-173301D02*
X245560D01*
G01X261532Y-179426D02*
Y-161926D01*
X271576Y-179426D01*
Y-161926D01*
G01X279469Y-177093D02*
X281216Y-178551D01*
X283181Y-179426D01*
X284927D01*
X286674Y-178551D01*
X287984Y-177093D01*
X288639Y-175051D01*
X288202Y-173010D01*
X287111Y-171259D01*
X285146Y-170093D01*
X282526Y-169509D01*
X280997Y-168343D01*
X280342Y-166301D01*
X280779Y-164259D01*
X281871Y-162801D01*
X283399Y-161926D01*
X284927D01*
X286456Y-162509D01*
X287766Y-163968D01*
G01X298934Y-161926D02*
X304174D01*
G01X301554D02*
Y-179426D01*
G01X298934D02*
X304174D01*
G01X319054Y-161926D02*
Y-179426D01*
G01X314032Y-161926D02*
X324076D01*
G01X333934D02*
X339174D01*
G01X336554D02*
Y-179426D01*
G01X333934D02*
X339174D01*
G01X354054D02*
X352307Y-179134D01*
X350779Y-177968D01*
X349469Y-176218D01*
X348595Y-174176D01*
X348159Y-171843D01*
Y-169509D01*
X348595Y-167176D01*
X349469Y-165134D01*
X350779Y-163385D01*
X352307Y-162218D01*
X354054Y-161926D01*
X355800Y-162218D01*
X357329Y-163385D01*
X358639Y-165134D01*
X359513Y-167176D01*
X359949Y-169509D01*
Y-171843D01*
X359513Y-174176D01*
X358639Y-176218D01*
X357329Y-177968D01*
X355800Y-179134D01*
X354054Y-179426D01*
G01X366532D02*
Y-161926D01*
X376576Y-179426D01*
Y-161926D01*
G01X408300Y-170093D02*
X409174Y-169218D01*
X409829Y-167760D01*
X410266Y-165717D01*
X409829Y-163968D01*
X408956Y-162801D01*
X407427Y-161926D01*
X401532D01*
Y-179426D01*
X408737D01*
X410266Y-178260D01*
X411139Y-176509D01*
X411576Y-174468D01*
X411139Y-172426D01*
X409829Y-170676D01*
X408300Y-170093D01*
X401532D01*
G01X424054Y-179426D02*
X422307Y-179134D01*
X420779Y-177968D01*
X419469Y-176218D01*
X418595Y-174176D01*
X418159Y-171843D01*
Y-169509D01*
X418595Y-167176D01*
X419469Y-165134D01*
X420779Y-163385D01*
X422307Y-162218D01*
X424054Y-161926D01*
X425800Y-162218D01*
X427329Y-163385D01*
X428639Y-165134D01*
X429513Y-167176D01*
X429949Y-169509D01*
Y-171843D01*
X429513Y-174176D01*
X428639Y-176218D01*
X427329Y-177968D01*
X425800Y-179134D01*
X424054Y-179426D01*
G01X436095D02*
X441554Y-161926D01*
X447013Y-179426D01*
G01X445047Y-173301D02*
X438060D01*
G01X454687Y-179426D02*
Y-161926D01*
X460146D01*
X461892Y-162801D01*
X462984Y-163968D01*
X463421Y-166301D01*
X462984Y-168635D01*
X461674Y-170093D01*
X460146Y-170968D01*
X454687D01*
G01X460146D02*
X463421Y-179426D01*
G01X471751D02*
Y-161926D01*
X476117D01*
X477864Y-162801D01*
X479174Y-163968D01*
X480266Y-165717D01*
X481139Y-167760D01*
X481357Y-170676D01*
X481139Y-173593D01*
X480266Y-175635D01*
X479174Y-177385D01*
X477864Y-178551D01*
X476117Y-179426D01*
X471751D01*
G01X208377Y-134426D02*
Y-116926D01*
X214054Y-131509D01*
X219731Y-116926D01*
Y-134426D01*
G01X231554D02*
X230244Y-134134D01*
X228934Y-132968D01*
X228060Y-130926D01*
X227624Y-128593D01*
X228060Y-126259D01*
X228934Y-124218D01*
X230244Y-123051D01*
X231554Y-122760D01*
X232864Y-123051D01*
X234174Y-124218D01*
X235047Y-126259D01*
X235266Y-128593D01*
X235047Y-130926D01*
X234174Y-132968D01*
X232864Y-134134D01*
X231554Y-134426D01*
G01X252984Y-116926D02*
Y-134426D01*
G01Y-131802D02*
X252111Y-133260D01*
X250800Y-134134D01*
X249272Y-134426D01*
X247526Y-133843D01*
X246216Y-132385D01*
X245342Y-130635D01*
X245124Y-128593D01*
X245342Y-126551D01*
X246216Y-124801D01*
X247526Y-123343D01*
X249272Y-122760D01*
X250800Y-123051D01*
X251892Y-123635D01*
X252984Y-124801D01*
G01X263279Y-126551D02*
X270266D01*
X269611Y-124509D01*
X268519Y-123343D01*
X266991Y-122760D01*
X265462Y-123051D01*
X264152Y-123926D01*
X263279Y-125968D01*
X262842Y-127718D01*
Y-129468D01*
X263279Y-131218D01*
X264371Y-132968D01*
X265681Y-134134D01*
X267209Y-134426D01*
X268737Y-133843D01*
X270266Y-132093D01*
G01X284054Y-134426D02*
Y-116926D01*
G01X536554Y-179426D02*
Y-161926D01*
X533934Y-165426D01*
G01Y-179426D02*
X539174D01*
G01X549906Y-164843D02*
X551216Y-163093D01*
X552744Y-162218D01*
X554491Y-161926D01*
X556674Y-162509D01*
X558202Y-163968D01*
X558639Y-165717D01*
X558421Y-167468D01*
X557547Y-168926D01*
X553181Y-171843D01*
X551216Y-173884D01*
X549906Y-176802D01*
X549469Y-179426D01*
X558639D01*
G01X566751Y-176802D02*
X568060Y-178260D01*
X569589Y-179134D01*
X571554Y-179426D01*
X573519Y-178843D01*
X575047Y-177676D01*
X576139Y-175635D01*
X576357Y-173301D01*
X575921Y-170968D01*
X574829Y-169509D01*
X573300Y-168343D01*
X571772Y-168051D01*
X570244Y-168343D01*
X568279Y-169509D01*
X568934Y-161926D01*
X574829D01*
G01X584906Y-164843D02*
X586216Y-163093D01*
X587744Y-162218D01*
X589491Y-161926D01*
X591674Y-162509D01*
X593202Y-163968D01*
X593639Y-165717D01*
X593421Y-167468D01*
X592547Y-168926D01*
X588181Y-171843D01*
X586216Y-173884D01*
X584906Y-176802D01*
X584469Y-179426D01*
X593639D01*
G01X601751Y-175926D02*
X603060Y-177968D01*
X604807Y-179134D01*
X606772Y-179426D01*
X608519Y-179134D01*
X610266Y-177676D01*
X611357Y-175926D01*
X611576Y-174176D01*
X611139Y-172135D01*
X609611Y-170676D01*
X608082Y-170093D01*
X606117D01*
G01X608082D02*
X609392Y-169218D01*
X610484Y-167760D01*
X610921Y-166010D01*
X610484Y-164259D01*
X609392Y-162801D01*
X607427Y-161926D01*
X605462Y-162218D01*
X603497Y-163385D01*
G01X523437Y-134426D02*
Y-116926D01*
X528677D01*
X530424Y-117801D01*
X531734Y-119843D01*
X532171Y-122176D01*
X531734Y-124509D01*
X530642Y-126259D01*
X528677Y-127135D01*
X523437D01*
G01X550107Y-118385D02*
X548797Y-117509D01*
X547269Y-116926D01*
X545522D01*
X543557Y-117801D01*
X542029Y-119259D01*
X540937Y-121010D01*
X540064Y-123926D01*
X539845Y-126551D01*
X540282Y-129176D01*
X540937Y-130926D01*
X542247Y-132676D01*
X543776Y-133843D01*
X545304Y-134426D01*
X546832D01*
X548361Y-133843D01*
X549671Y-132968D01*
X550763Y-131802D01*
G01X564550Y-125093D02*
X565424Y-124218D01*
X566079Y-122760D01*
X566516Y-120717D01*
X566079Y-118968D01*
X565206Y-117801D01*
X563677Y-116926D01*
X557782D01*
Y-134426D01*
X564987D01*
X566516Y-133260D01*
X567389Y-131509D01*
X567826Y-129468D01*
X567389Y-127426D01*
X566079Y-125676D01*
X564550Y-125093D01*
X557782D01*
G01X573754Y-140259D02*
X586854D01*
G01X592782Y-134426D02*
Y-116926D01*
X602826Y-134426D01*
Y-116926D01*
G01X615304Y-134426D02*
X613557Y-134134D01*
X612029Y-132968D01*
X610719Y-131218D01*
X609845Y-129176D01*
X609409Y-126843D01*
Y-124509D01*
X609845Y-122176D01*
X610719Y-120134D01*
X612029Y-118385D01*
X613557Y-117218D01*
X615304Y-116926D01*
X617050Y-117218D01*
X618579Y-118385D01*
X619889Y-120134D01*
X620763Y-122176D01*
X621199Y-124509D01*
Y-126843D01*
X620763Y-129176D01*
X619889Y-131218D01*
X618579Y-132968D01*
X617050Y-134134D01*
X615304Y-134426D01*
G01X697854Y-179426D02*
Y-161926D01*
X695234Y-165426D01*
G01Y-179426D02*
X700474D01*
G01X666145Y-116926D02*
X671604Y-134426D01*
X677063Y-116926D01*
G01X693471Y-134426D02*
X684737D01*
Y-116926D01*
X693471D01*
G01X689977Y-125384D02*
X684737D01*
G01X702237Y-134426D02*
Y-116926D01*
X707696D01*
X709442Y-117801D01*
X710534Y-118968D01*
X710971Y-121301D01*
X710534Y-123635D01*
X709224Y-125093D01*
X707696Y-125968D01*
X702237D01*
G01X707696D02*
X710971Y-134426D01*
G01X724104Y-135009D02*
X723667Y-134718D01*
Y-134134D01*
X724104Y-133843D01*
X724541Y-134134D01*
Y-134718D01*
X724104Y-135009D01*
G01X799687Y-161926D02*
Y-179426D01*
X808421D01*
G01X817406Y-164843D02*
X818716Y-163093D01*
X820244Y-162218D01*
X821991Y-161926D01*
X824174Y-162509D01*
X825702Y-163968D01*
X826139Y-165717D01*
X825921Y-167468D01*
X825047Y-168926D01*
X820681Y-171843D01*
X818716Y-173884D01*
X817406Y-176802D01*
X816969Y-179426D01*
X826139D01*
G01X840364Y-170676D02*
X844731D01*
Y-175926D01*
X843421Y-177676D01*
X841892Y-178843D01*
X839709Y-179426D01*
X837526Y-178843D01*
X835997Y-177676D01*
X834687Y-175926D01*
X833814Y-173884D01*
X833377Y-171551D01*
Y-169509D01*
X833814Y-167760D01*
X834687Y-165717D01*
X835997Y-163968D01*
X837307Y-162801D01*
X839054Y-161926D01*
X840582D01*
X842329Y-162509D01*
X843639Y-163676D01*
G01X851532Y-179426D02*
Y-161926D01*
X861576Y-179426D01*
Y-161926D01*
G01X869251Y-179426D02*
Y-161926D01*
X873617D01*
X875364Y-162801D01*
X876674Y-163968D01*
X877766Y-165717D01*
X878639Y-167760D01*
X878857Y-170676D01*
X878639Y-173593D01*
X877766Y-175635D01*
X876674Y-177385D01*
X875364Y-178551D01*
X873617Y-179426D01*
X869251D01*
G01X790937Y-116926D02*
Y-134426D01*
X799671D01*
G01X816734D02*
Y-122760D01*
G01Y-124801D02*
X815861Y-123635D01*
X814550Y-123051D01*
X813022Y-122760D01*
X811494Y-123343D01*
X810184Y-124509D01*
X809310Y-126259D01*
X808874Y-128593D01*
X809310Y-130926D01*
X810184Y-132676D01*
X811494Y-133843D01*
X813022Y-134426D01*
X814550Y-134134D01*
X815861Y-133260D01*
X816734Y-132093D01*
G01X825719Y-139676D02*
X827029Y-140259D01*
X828776Y-139676D01*
X829867Y-138510D01*
X830741Y-137051D01*
X832050Y-132385D01*
X834889Y-122760D01*
G01X827902D02*
X832050Y-132385D01*
G01X844529Y-126551D02*
X851516D01*
X850861Y-124509D01*
X849769Y-123343D01*
X848241Y-122760D01*
X846712Y-123051D01*
X845402Y-123926D01*
X844529Y-125968D01*
X844092Y-127718D01*
Y-129468D01*
X844529Y-131218D01*
X845621Y-132968D01*
X846931Y-134134D01*
X848459Y-134426D01*
X849987Y-133843D01*
X851516Y-132093D01*
G01X862247Y-134426D02*
Y-122760D01*
G01Y-125093D02*
X863339Y-123926D01*
X864431Y-123051D01*
X865959Y-122760D01*
X867050Y-123051D01*
X868361Y-123926D01*
G01X879529Y-132385D02*
X880621Y-133551D01*
X882149Y-134426D01*
X883459D01*
X884769Y-133843D01*
X885642Y-132968D01*
X886079Y-131802D01*
X885861Y-130051D01*
X884987Y-129176D01*
X881057Y-127426D01*
X880184Y-125384D01*
X880621Y-123926D01*
X881494Y-123051D01*
X882804Y-122760D01*
X884114Y-123051D01*
X885424Y-123926D01*
G01X924737Y-175926D02*
X925829Y-177676D01*
X927139Y-178843D01*
X928667Y-179426D01*
X930414Y-178843D01*
X931724Y-177676D01*
X933034Y-175926D01*
X933471Y-173593D01*
Y-161926D01*
G01X946604Y-179426D02*
X944857Y-179134D01*
X943329Y-177968D01*
X942019Y-176218D01*
X941145Y-174176D01*
X940709Y-171843D01*
Y-169509D01*
X941145Y-167176D01*
X942019Y-165134D01*
X943329Y-163385D01*
X944857Y-162218D01*
X946604Y-161926D01*
X948350Y-162218D01*
X949879Y-163385D01*
X951189Y-165134D01*
X952063Y-167176D01*
X952499Y-169509D01*
Y-171843D01*
X952063Y-174176D01*
X951189Y-176218D01*
X949879Y-177968D01*
X948350Y-179134D01*
X946604Y-179426D01*
G01X959519Y-177093D02*
X961266Y-178551D01*
X963231Y-179426D01*
X964977D01*
X966724Y-178551D01*
X968034Y-177093D01*
X968689Y-175051D01*
X968252Y-173010D01*
X967161Y-171259D01*
X965196Y-170093D01*
X962576Y-169509D01*
X961047Y-168343D01*
X960392Y-166301D01*
X960829Y-164259D01*
X961921Y-162801D01*
X963449Y-161926D01*
X964977D01*
X966506Y-162509D01*
X967816Y-163968D01*
G01X985971Y-179426D02*
X977237D01*
Y-161926D01*
X985971D01*
G01X982477Y-170384D02*
X977237D01*
G01X994737Y-179426D02*
Y-161926D01*
X999977D01*
X1001724Y-162801D01*
X1003034Y-164843D01*
X1003471Y-167176D01*
X1003034Y-169509D01*
X1001942Y-171259D01*
X999977Y-172135D01*
X994737D01*
G01X1012019Y-179426D02*
Y-161926D01*
G01X1021189D02*
Y-179426D01*
G01Y-170676D02*
X1012019D01*
G01X1047237Y-161926D02*
Y-179426D01*
X1055971D01*
G01X1063645D02*
X1069104Y-161926D01*
X1074563Y-179426D01*
G01X1072597Y-173301D02*
X1065610D01*
G01X1081801Y-161926D02*
Y-174468D01*
X1082674Y-177093D01*
X1084421Y-178843D01*
X1086604Y-179426D01*
X1088787Y-178843D01*
X1090534Y-177093D01*
X1091407Y-174468D01*
Y-161926D01*
G01X941801Y-134426D02*
Y-116926D01*
X946167D01*
X947914Y-117801D01*
X949224Y-118968D01*
X950316Y-120717D01*
X951189Y-122760D01*
X951407Y-125676D01*
X951189Y-128593D01*
X950316Y-130635D01*
X949224Y-132385D01*
X947914Y-133551D01*
X946167Y-134426D01*
X941801D01*
G01X960829Y-126551D02*
X967816D01*
X967161Y-124509D01*
X966069Y-123343D01*
X964541Y-122760D01*
X963012Y-123051D01*
X961702Y-123926D01*
X960829Y-125968D01*
X960392Y-127718D01*
Y-129468D01*
X960829Y-131218D01*
X961921Y-132968D01*
X963231Y-134134D01*
X964759Y-134426D01*
X966287Y-133843D01*
X967816Y-132093D01*
G01X978329Y-132385D02*
X979421Y-133551D01*
X980949Y-134426D01*
X982259D01*
X983569Y-133843D01*
X984442Y-132968D01*
X984879Y-131802D01*
X984661Y-130051D01*
X983787Y-129176D01*
X979857Y-127426D01*
X978984Y-125384D01*
X979421Y-123926D01*
X980294Y-123051D01*
X981604Y-122760D01*
X982914Y-123051D01*
X984224Y-123926D01*
G01X999104Y-122760D02*
Y-134426D01*
G01Y-118093D02*
X998667Y-117801D01*
Y-117218D01*
X999104Y-116926D01*
X999541Y-117218D01*
Y-117801D01*
X999104Y-118093D01*
G01X1013547Y-138801D02*
X1015076Y-139968D01*
X1016822Y-140259D01*
X1018350Y-139968D01*
X1019661Y-138510D01*
X1020534Y-136468D01*
Y-122760D01*
G01Y-125093D02*
X1019661Y-123926D01*
X1018350Y-123051D01*
X1016822Y-122760D01*
X1015076Y-123343D01*
X1013984Y-124509D01*
X1013110Y-126551D01*
X1012674Y-128593D01*
X1012892Y-130343D01*
X1013766Y-132385D01*
X1015076Y-133843D01*
X1016822Y-134426D01*
X1018132Y-134134D01*
X1019661Y-132968D01*
X1020534Y-131802D01*
G01X1030392Y-134426D02*
Y-122760D01*
G01Y-125676D02*
X1031266Y-124218D01*
X1032576Y-123051D01*
X1034322Y-122760D01*
X1035850Y-123051D01*
X1037161Y-124218D01*
X1037816Y-126259D01*
Y-134426D01*
G01X1048329Y-126551D02*
X1055316D01*
X1054661Y-124509D01*
X1053569Y-123343D01*
X1052041Y-122760D01*
X1050512Y-123051D01*
X1049202Y-123926D01*
X1048329Y-125968D01*
X1047892Y-127718D01*
Y-129468D01*
X1048329Y-131218D01*
X1049421Y-132968D01*
X1050731Y-134134D01*
X1052259Y-134426D01*
X1053787Y-133843D01*
X1055316Y-132093D01*
G01X1066047Y-134426D02*
Y-122760D01*
G01Y-125093D02*
X1067139Y-123926D01*
X1068231Y-123051D01*
X1069759Y-122760D01*
X1070850Y-123051D01*
X1072161Y-123926D01*
G01X1112804Y-179426D02*
Y-161926D01*
X1110184Y-165426D01*
G01Y-179426D02*
X1115424D01*
G01X1130304Y-161926D02*
X1128557Y-162509D01*
X1127247Y-163968D01*
X1126374Y-165717D01*
X1125719Y-168051D01*
X1125501Y-170676D01*
X1125719Y-173301D01*
X1126374Y-175635D01*
X1127247Y-177385D01*
X1128557Y-178843D01*
X1130304Y-179426D01*
X1132050Y-178843D01*
X1133361Y-177385D01*
X1134234Y-175635D01*
X1134889Y-173301D01*
X1135107Y-170676D01*
X1134889Y-168051D01*
X1134234Y-165717D01*
X1133361Y-163968D01*
X1132050Y-162509D01*
X1130304Y-161926D01*
G01X1143874Y-180009D02*
X1151734Y-161926D01*
G01X1165304Y-179426D02*
Y-161926D01*
X1162684Y-165426D01*
G01Y-179426D02*
X1167924D01*
G01X1179092Y-177385D02*
X1180621Y-178843D01*
X1182367Y-179426D01*
X1184114Y-178843D01*
X1185642Y-177093D01*
X1186734Y-174468D01*
X1187171Y-171843D01*
Y-168635D01*
X1186734Y-166010D01*
X1185642Y-163676D01*
X1184332Y-162509D01*
X1182804Y-161926D01*
X1181057Y-162509D01*
X1179747Y-163676D01*
X1178874Y-165426D01*
X1178437Y-167760D01*
X1178874Y-169801D01*
X1179966Y-171843D01*
X1181276Y-173010D01*
X1182804Y-173301D01*
X1184550Y-172718D01*
X1185861Y-171259D01*
X1187171Y-168635D01*
G01X1196374Y-180009D02*
X1204234Y-161926D01*
G01X1213656Y-164843D02*
X1214966Y-163093D01*
X1216494Y-162218D01*
X1218241Y-161926D01*
X1220424Y-162509D01*
X1221952Y-163968D01*
X1222389Y-165717D01*
X1222171Y-167468D01*
X1221297Y-168926D01*
X1216931Y-171843D01*
X1214966Y-173884D01*
X1213656Y-176802D01*
X1213219Y-179426D01*
X1222389D01*
G01X1235304Y-161926D02*
X1233557Y-162509D01*
X1232247Y-163968D01*
X1231374Y-165717D01*
X1230719Y-168051D01*
X1230501Y-170676D01*
X1230719Y-173301D01*
X1231374Y-175635D01*
X1232247Y-177385D01*
X1233557Y-178843D01*
X1235304Y-179426D01*
X1237050Y-178843D01*
X1238361Y-177385D01*
X1239234Y-175635D01*
X1239889Y-173301D01*
X1240107Y-170676D01*
X1239889Y-168051D01*
X1239234Y-165717D01*
X1238361Y-163968D01*
X1237050Y-162509D01*
X1235304Y-161926D01*
G01X1252804Y-179426D02*
Y-161926D01*
X1250184Y-165426D01*
G01Y-179426D02*
X1255424D01*
G01X1266156Y-164843D02*
X1267466Y-163093D01*
X1268994Y-162218D01*
X1270741Y-161926D01*
X1272924Y-162509D01*
X1274452Y-163968D01*
X1274889Y-165717D01*
X1274671Y-167468D01*
X1273797Y-168926D01*
X1269431Y-171843D01*
X1267466Y-173884D01*
X1266156Y-176802D01*
X1265719Y-179426D01*
X1274889D01*
G01X1160501Y-134426D02*
Y-116926D01*
X1164867D01*
X1166614Y-117801D01*
X1167924Y-118968D01*
X1169016Y-120717D01*
X1169889Y-122760D01*
X1170107Y-125676D01*
X1169889Y-128593D01*
X1169016Y-130635D01*
X1167924Y-132385D01*
X1166614Y-133551D01*
X1164867Y-134426D01*
X1160501D01*
G01X1186734D02*
Y-122760D01*
G01Y-124801D02*
X1185861Y-123635D01*
X1184550Y-123051D01*
X1183022Y-122760D01*
X1181494Y-123343D01*
X1180184Y-124509D01*
X1179310Y-126259D01*
X1178874Y-128593D01*
X1179310Y-130926D01*
X1180184Y-132676D01*
X1181494Y-133843D01*
X1183022Y-134426D01*
X1184550Y-134134D01*
X1185861Y-133260D01*
X1186734Y-132093D01*
G01X1200304Y-116926D02*
Y-134426D01*
G01X1197247Y-122760D02*
X1203361D01*
G01X1214529Y-126551D02*
X1221516D01*
X1220861Y-124509D01*
X1219769Y-123343D01*
X1218241Y-122760D01*
X1216712Y-123051D01*
X1215402Y-123926D01*
X1214529Y-125968D01*
X1214092Y-127718D01*
Y-129468D01*
X1214529Y-131218D01*
X1215621Y-132968D01*
X1216931Y-134134D01*
X1218459Y-134426D01*
X1219987Y-133843D01*
X1221516Y-132093D01*
M02*
